# T6G (Grand Teton) — schematic netlist excerpt (pin names and nets, part order shuffled) for the footprints in the layout excerpt that follows; sources: Cadence DE-HDL packaged netlist, KiCad conversion of 04192023_DAF0TMB3IC0_F0TG_MB_C_brd_V02_OCP.brd

R764  Q_RES  84.5K 1% CHIP  pkg 0402LF  page 91 : A = PD_CHF_CPU0_DIMM_SAA ; B = GND
R6737  Q_RES  0 5% CHIP  pkg 0201LF  page 184 : A = SMB_RT_CPU1_P1_R_SCL ; B = SMB_RT_CPU1_P1_SCL
PC120_6  Q_CAP  22UF 4V 20% X6S  pkg C0805  page 203 : A = PVDDCR_CPU1_P0 ; B = GND

(kicad_pcb
	(version 20260206)
	(generator "pcbnew")
	(generator_version "10.0")
	(general
		(thickness 1.6)
		(legacy_teardrops no)
	)
	(paper "A4")
	(title_block
		(title "04192023_DAF0TMB3IC0_F0TG_MB_C_brd_V02_OCP.brd")
		(comment 1 "Grand Teton / footprints 7140-7142 of 8354")
	)
	(layers
		(0 "F.Cu" signal "TOP")
		(4 "In1.Cu" signal "GND")
		(6 "In2.Cu" signal "IN1")
		(8 "In3.Cu" signal "GND1")
		(10 "In4.Cu" signal "IN2")
		(12 "In5.Cu" signal "GND2")
		(14 "In6.Cu" signal "IN3")
		(16 "In7.Cu" signal "GND3")
		(18 "In8.Cu" signal "VCC")
		(20 "In9.Cu" signal "VCC1")
		(22 "In10.Cu" signal "GND4")
		(24 "In11.Cu" signal "IN4")
		(26 "In12.Cu" signal "GND5")
		(28 "In13.Cu" signal "IN5")
		(30 "In14.Cu" signal "GND6")
		(32 "In15.Cu" signal "IN6")
		(34 "In16.Cu" signal "GND7")
		(2 "B.Cu" signal "BOTTOM")
		(9 "F.Adhes" user "F.Adhesive")
		(11 "B.Adhes" user "B.Adhesive")
		(13 "F.Paste" user "Package Geometry/Pastemask Top")
		(15 "B.Paste" user "Package Geometry/Pastemask Bottom")
		(5 "F.SilkS" user "Ref Des/Silkscreen Top")
		(7 "B.SilkS" user "Ref Des/Silkscreen Bottom")
		(1 "F.Mask" user "Board Geometry/Soldermask Top")
		(3 "B.Mask" user "Board Geometry/Soldermask Bottom")
		(17 "Dwgs.User" user "User.Drawings")
		(19 "Cmts.User" user "User.Comments")
		(21 "Eco1.User" user "User.Eco1")
		(23 "Eco2.User" user "User.Eco2")
		(25 "Edge.Cuts" user "Board Geometry/Outline")
		(27 "Margin" user)
		(31 "F.CrtYd" user "Package Geometry/Place Bound Top")
		(29 "B.CrtYd" user "Package Geometry/Place Bound Bottom")
		(35 "F.Fab" user "Ref Des/Assembly Top")
		(33 "B.Fab" user "Ref Des/Assembly Bottom")
	)
	(footprint ""
		(layer "B.Cu")
		(at 218.059 -337.312 180)
		(property "Reference" "R6737"
			(at 0 0 0)
			(layer "B.SilkS")
			(hide yes)
			(effects
				(font
					(size 1.27 1.27)
				)
				(justify mirror)
			)
		)
		(property "Value" ""
			(at 0 0 0)
			(layer "B.Fab")
			(effects
				(font
					(size 1.27 1.27)
				)
				(justify mirror)
			)
		)
		(duplicate_pad_numbers_are_jumpers no)
		(fp_line
			(start 0.32512 0.175006)
			(end 0.32512 -0.175006)
			(stroke
				(width 0.1)
				(type default)
			)
			(layer "B.Fab")
		)
		(fp_line
			(start 0.32512 -0.175006)
			(end -0.32512 -0.175006)
			(stroke
				(width 0.1)
				(type default)
			)
			(layer "B.Fab")
		)
		(fp_line
			(start -0.32512 0.175006)
			(end 0.32512 0.175006)
			(stroke
				(width 0.1)
				(type default)
			)
			(layer "B.Fab")
		)
		(fp_line
			(start -0.32512 -0.175006)
			(end -0.32512 0.175006)
			(stroke
				(width 0.1)
				(type default)
			)
			(layer "B.Fab")
		)
		(pad "1" smd rect
			(at 0.2667 0)
			(size 0.3048 0.381)
			(layers "B.Cu" "B.Mask" "B.Paste")
			(net "SMB_RT_CPU1_P1_R_SCL")
		)
		(pad "2" smd rect
			(at -0.2667 0 180)
			(size 0.3048 0.381)
			(layers "B.Cu" "B.Mask" "B.Paste")
			(net "SMB_RT_CPU1_P1_SCL")
		)
	)
	(footprint ""
		(layer "B.Cu")
		(at 348.56547 -331.274928 -90)
		(property "Reference" "PC120_6"
			(at 0 0 90)
			(layer "B.SilkS")
			(hide yes)
			(effects
				(font
					(size 1.27 1.27)
				)
				(justify mirror)
			)
		)
		(property "Value" ""
			(at 0 0 90)
			(layer "B.Fab")
			(effects
				(font
					(size 1.27 1.27)
				)
				(justify mirror)
			)
		)
		(duplicate_pad_numbers_are_jumpers no)
		(fp_line
			(start -1.524 0.762)
			(end 1.524 0.762)
			(stroke
				(width 0.1524)
				(type default)
			)
			(layer "B.SilkS")
		)
		(fp_line
			(start 1.524 0.762)
			(end 1.524 -0.762)
			(stroke
				(width 0.1524)
				(type default)
			)
			(layer "B.SilkS")
		)
		(fp_line
			(start -1.524 -0.762)
			(end -1.524 0.762)
			(stroke
				(width 0.1524)
				(type default)
			)
			(layer "B.SilkS")
		)
		(fp_line
			(start 1.524 -0.762)
			(end -1.524 -0.762)
			(stroke
				(width 0.1524)
				(type default)
			)
			(layer "B.SilkS")
		)
		(fp_line
			(start -1.1049 0.724916)
			(end -1.1049 -0.724916)
			(stroke
				(width 0.1)
				(type default)
			)
			(layer "B.Fab")
		)
		(fp_line
			(start 1.1049 0.724916)
			(end -1.1049 0.724916)
			(stroke
				(width 0.1)
				(type default)
			)
			(layer "B.Fab")
		)
		(fp_line
			(start -1.1049 -0.724916)
			(end 1.1049 -0.724916)
			(stroke
				(width 0.1)
				(type default)
			)
			(layer "B.Fab")
		)
		(fp_line
			(start 1.1049 -0.724916)
			(end 1.1049 0.724916)
			(stroke
				(width 0.1)
				(type default)
			)
			(layer "B.Fab")
		)
		(pad "1" smd rect
			(at 0.889 0 270)
			(size 1.016 1.27)
			(layers "B.Cu" "B.Mask" "B.Paste")
			(net "PVDDCR_CPU1_P0")
		)
		(pad "2" smd rect
			(at -0.889 0 270)
			(size 1.016 1.27)
			(layers "B.Cu" "B.Mask" "B.Paste")
			(net "GND")
		)
	)
	(footprint ""
		(layer "B.Cu")
		(at 266.30376 -194.88531 180)
		(property "Reference" "R764"
			(at 0 0 0)
			(layer "B.SilkS")
			(hide yes)
			(effects
				(font
					(size 1.27 1.27)
				)
				(justify mirror)
			)
		)
		(property "Value" ""
			(at 0 0 0)
			(layer "B.Fab")
			(effects
				(font
					(size 1.27 1.27)
				)
				(justify mirror)
			)
		)
		(duplicate_pad_numbers_are_jumpers no)
		(fp_line
			(start 0.7874 0.4064)
			(end 0.7874 -0.4064)
			(stroke
				(width 0.1524)
				(type default)
			)
			(layer "B.SilkS")
		)
		(fp_line
			(start 0.7874 -0.4064)
			(end -0.7874 -0.4064)
			(stroke
				(width 0.1524)
				(type default)
			)
			(layer "B.SilkS")
		)
		(fp_line
			(start -0.7874 0.4064)
			(end 0.7874 0.4064)
			(stroke
				(width 0.1524)
				(type default)
			)
			(layer "B.SilkS")
		)
		(fp_line
			(start -0.7874 -0.4064)
			(end -0.7874 0.4064)
			(stroke
				(width 0.1524)
				(type default)
			)
			(layer "B.SilkS")
		)
		(fp_line
			(start 0.67945 0.3048)
			(end 0.67945 -0.305054)
			(stroke
				(width 0.1)
				(type default)
			)
			(layer "B.Fab")
		)
		(fp_line
			(start 0.67945 -0.305054)
			(end 0.12065 -0.305054)
			(stroke
				(width 0.1)
				(type default)
			)
			(layer "B.Fab")
		)
		(fp_line
			(start 0.12065 0.3048)
			(end 0.67945 0.3048)
			(stroke
				(width 0.1)
				(type default)
			)
			(layer "B.Fab")
		)
		(fp_line
			(start 0.12065 0.2794)
			(end 0.12065 0.3048)
			(stroke
				(width 0.1)
				(type default)
			)
			(layer "B.Fab")
		)
		(fp_line
			(start 0.12065 -0.2794)
			(end -0.12065 -0.2794)
			(stroke
				(width 0.1)
				(type default)
			)
			(layer "B.Fab")
		)
		(fp_line
			(start 0.12065 -0.305054)
			(end 0.12065 -0.2794)
			(stroke
				(width 0.1)
				(type default)
			)
			(layer "B.Fab")
		)
		(fp_line
			(start -0.120396 0.3048)
			(end -0.120396 0.2794)
			(stroke
				(width 0.1)
				(type default)
			)
			(layer "B.Fab")
		)
		(fp_line
			(start -0.120396 0.2794)
			(end 0.12065 0.2794)
			(stroke
				(width 0.1)
				(type default)
			)
			(layer "B.Fab")
		)
		(fp_line
			(start -0.12065 -0.2794)
			(end -0.12065 -0.3048)
			(stroke
				(width 0.1)
				(type default)
			)
			(layer "B.Fab")
		)
		(fp_line
			(start -0.12065 -0.3048)
			(end -0.67945 -0.3048)
			(stroke
				(width 0.1)
				(type default)
			)
			(layer "B.Fab")
		)
		(fp_line
			(start -0.67945 0.3048)
			(end -0.120396 0.3048)
			(stroke
				(width 0.1)
				(type default)
			)
			(layer "B.Fab")
		)
		(fp_line
			(start -0.67945 -0.3048)
			(end -0.67945 0.3048)
			(stroke
				(width 0.1)
				(type default)
			)
			(layer "B.Fab")
		)
		(pad "1" smd circle
			(at 0.40005 0)
			(size 0 0)
			(layers "B.Cu" "B.Mask" "B.Paste")
			(net "PD_CHF_CPU0_DIMM_SAA")
		)
		(pad "2" smd circle
			(at -0.40005 0)
			(size 0 0)
			(layers "B.Cu" "B.Mask" "B.Paste")
			(net "GND")
		)
	)
)
